# S9S_MB_2U (Grand Teton) — schematic netlist excerpt (pin names and nets, part order shuffled) for the footprints in the layout excerpt that follows; sources: Cadence DE-HDL packaged netlist, KiCad conversion of 03242023_DA0F0TMBIJ0_F0T_Motherboard_J_brd_V01_OCP.brd

C2323  Q_CAP  1UF 25V 10% EMPTY  pkg C0402  page 196 : A = P3V3_AUX ; B = GND
R999  Q_RES  0 5% CHIP  pkg 0402LF  page 235 : A = FM_SMB_PEHPCPU1_PCIE_ALERT_N ; B = FM_SMB_PEHPCPU1_PCIE_ALERT_R_N

(kicad_pcb
	(version 20260206)
	(generator "pcbnew")
	(generator_version "10.0")
	(general
		(thickness 1.6)
		(legacy_teardrops no)
	)
	(paper "A4")
	(title_block
		(title "03242023_DA0F0TMBIJ0_F0T_Motherboard_J_brd_V01_OCP.brd")
		(comment 1 "Grand Teton / footprints 5724-5725 of 6105")
	)
	(layers
		(0 "F.Cu" signal "TOP")
		(4 "In1.Cu" signal "GND")
		(6 "In2.Cu" signal "IN1")
		(8 "In3.Cu" signal "GND1")
		(10 "In4.Cu" signal "IN2")
		(12 "In5.Cu" signal "GND2")
		(14 "In6.Cu" signal "IN3")
		(16 "In7.Cu" signal "GND3")
		(18 "In8.Cu" signal "VCC")
		(20 "In9.Cu" signal "VCC1")
		(22 "In10.Cu" signal "GND4")
		(24 "In11.Cu" signal "IN4")
		(26 "In12.Cu" signal "GND5")
		(28 "In13.Cu" signal "IN5")
		(30 "In14.Cu" signal "GND6")
		(32 "In15.Cu" signal "IN6")
		(34 "In16.Cu" signal "GND7")
		(2 "B.Cu" signal "BOTTOM")
		(9 "F.Adhes" user "F.Adhesive")
		(11 "B.Adhes" user "B.Adhesive")
		(13 "F.Paste" user "Package Geometry/Pastemask Top")
		(15 "B.Paste" user "Package Geometry/Pastemask Bottom")
		(5 "F.SilkS" user "Ref Des/Silkscreen Top")
		(7 "B.SilkS" user "Ref Des/Silkscreen Bottom")
		(1 "F.Mask" user "Board Geometry/Soldermask Top")
		(3 "B.Mask" user "Board Geometry/Soldermask Bottom")
		(17 "Dwgs.User" user "User.Drawings")
		(19 "Cmts.User" user "User.Comments")
		(21 "Eco1.User" user "User.Eco1")
		(23 "Eco2.User" user "User.Eco2")
		(25 "Edge.Cuts" user "Board Geometry/Outline")
		(27 "Margin" user)
		(31 "F.CrtYd" user "Package Geometry/Place Bound Top")
		(29 "B.CrtYd" user "Package Geometry/Place Bound Bottom")
		(35 "F.Fab" user "Ref Des/Assembly Top")
		(33 "B.Fab" user "Ref Des/Assembly Bottom")
	)
	(footprint ""
		(layer "B.Cu")
		(at 138.77798 -30.157928 -90)
		(property "Reference" "C2323"
			(at 0 0 90)
			(layer "B.SilkS")
			(hide yes)
			(effects
				(font
					(size 1.27 1.27)
				)
				(justify mirror)
			)
		)
		(property "Value" ""
			(at 0 0 90)
			(layer "B.Fab")
			(effects
				(font
					(size 1.27 1.27)
				)
				(justify mirror)
			)
		)
		(duplicate_pad_numbers_are_jumpers no)
		(fp_line
			(start -0.7874 0.4064)
			(end 0.7874 0.4064)
			(stroke
				(width 0.1524)
				(type default)
			)
			(layer "B.SilkS")
		)
		(fp_line
			(start 0.7874 0.4064)
			(end 0.7874 -0.4064)
			(stroke
				(width 0.1524)
				(type default)
			)
			(layer "B.SilkS")
		)
		(fp_line
			(start -0.7874 -0.4064)
			(end -0.7874 0.4064)
			(stroke
				(width 0.1524)
				(type default)
			)
			(layer "B.SilkS")
		)
		(fp_line
			(start 0.7874 -0.4064)
			(end -0.7874 -0.4064)
			(stroke
				(width 0.1524)
				(type default)
			)
			(layer "B.SilkS")
		)
		(fp_line
			(start -0.67945 0.3048)
			(end -0.120396 0.3048)
			(stroke
				(width 0.1)
				(type default)
			)
			(layer "B.Fab")
		)
		(fp_line
			(start -0.120396 0.3048)
			(end -0.120396 0.2794)
			(stroke
				(width 0.1)
				(type default)
			)
			(layer "B.Fab")
		)
		(fp_line
			(start 0.12065 0.3048)
			(end 0.67945 0.3048)
			(stroke
				(width 0.1)
				(type default)
			)
			(layer "B.Fab")
		)
		(fp_line
			(start 0.67945 0.3048)
			(end 0.67945 -0.305054)
			(stroke
				(width 0.1)
				(type default)
			)
			(layer "B.Fab")
		)
		(fp_line
			(start -0.120396 0.2794)
			(end 0.12065 0.2794)
			(stroke
				(width 0.1)
				(type default)
			)
			(layer "B.Fab")
		)
		(fp_line
			(start 0.12065 0.2794)
			(end 0.12065 0.3048)
			(stroke
				(width 0.1)
				(type default)
			)
			(layer "B.Fab")
		)
		(fp_line
			(start -0.12065 -0.2794)
			(end -0.12065 -0.3048)
			(stroke
				(width 0.1)
				(type default)
			)
			(layer "B.Fab")
		)
		(fp_line
			(start 0.12065 -0.2794)
			(end -0.12065 -0.2794)
			(stroke
				(width 0.1)
				(type default)
			)
			(layer "B.Fab")
		)
		(fp_line
			(start -0.67945 -0.3048)
			(end -0.67945 0.3048)
			(stroke
				(width 0.1)
				(type default)
			)
			(layer "B.Fab")
		)
		(fp_line
			(start -0.12065 -0.3048)
			(end -0.67945 -0.3048)
			(stroke
				(width 0.1)
				(type default)
			)
			(layer "B.Fab")
		)
		(fp_line
			(start 0.12065 -0.305054)
			(end 0.12065 -0.2794)
			(stroke
				(width 0.1)
				(type default)
			)
			(layer "B.Fab")
		)
		(fp_line
			(start 0.67945 -0.305054)
			(end 0.12065 -0.305054)
			(stroke
				(width 0.1)
				(type default)
			)
			(layer "B.Fab")
		)
		(pad "1" smd circle
			(at 0.40005 0 90)
			(size 0 0)
			(layers "B.Cu" "B.Mask" "B.Paste")
			(net "P3V3_AUX")
		)
		(pad "2" smd circle
			(at -0.40005 0 90)
			(size 0 0)
			(layers "B.Cu" "B.Mask" "B.Paste")
			(net "GND")
		)
	)
	(footprint ""
		(layer "B.Cu")
		(at 89.394284 -184.015888 90)
		(property "Reference" "R999"
			(at 0 0 90)
			(layer "B.SilkS")
			(hide yes)
			(effects
				(font
					(size 1.27 1.27)
				)
				(justify mirror)
			)
		)
		(property "Value" ""
			(at 0 0 90)
			(layer "B.Fab")
			(effects
				(font
					(size 1.27 1.27)
				)
				(justify mirror)
			)
		)
		(duplicate_pad_numbers_are_jumpers no)
		(fp_line
			(start 0.7874 -0.4064)
			(end -0.7874 -0.4064)
			(stroke
				(width 0.1524)
				(type default)
			)
			(layer "B.SilkS")
		)
		(fp_line
			(start -0.7874 -0.4064)
			(end -0.7874 0.4064)
			(stroke
				(width 0.1524)
				(type default)
			)
			(layer "B.SilkS")
		)
		(fp_line
			(start 0.7874 0.4064)
			(end 0.7874 -0.4064)
			(stroke
				(width 0.1524)
				(type default)
			)
			(layer "B.SilkS")
		)
		(fp_line
			(start -0.7874 0.4064)
			(end 0.7874 0.4064)
			(stroke
				(width 0.1524)
				(type default)
			)
			(layer "B.SilkS")
		)
		(fp_line
			(start 0.67945 -0.305054)
			(end 0.12065 -0.305054)
			(stroke
				(width 0.1)
				(type default)
			)
			(layer "B.Fab")
		)
		(fp_line
			(start 0.12065 -0.305054)
			(end 0.12065 -0.2794)
			(stroke
				(width 0.1)
				(type default)
			)
			(layer "B.Fab")
		)
		(fp_line
			(start -0.12065 -0.3048)
			(end -0.67945 -0.3048)
			(stroke
				(width 0.1)
				(type default)
			)
			(layer "B.Fab")
		)
		(fp_line
			(start -0.67945 -0.3048)
			(end -0.67945 0.3048)
			(stroke
				(width 0.1)
				(type default)
			)
			(layer "B.Fab")
		)
		(fp_line
			(start 0.12065 -0.2794)
			(end -0.12065 -0.2794)
			(stroke
				(width 0.1)
				(type default)
			)
			(layer "B.Fab")
		)
		(fp_line
			(start -0.12065 -0.2794)
			(end -0.12065 -0.3048)
			(stroke
				(width 0.1)
				(type default)
			)
			(layer "B.Fab")
		)
		(fp_line
			(start 0.12065 0.2794)
			(end 0.12065 0.3048)
			(stroke
				(width 0.1)
				(type default)
			)
			(layer "B.Fab")
		)
		(fp_line
			(start -0.120396 0.2794)
			(end 0.12065 0.2794)
			(stroke
				(width 0.1)
				(type default)
			)
			(layer "B.Fab")
		)
		(fp_line
			(start 0.67945 0.3048)
			(end 0.67945 -0.305054)
			(stroke
				(width 0.1)
				(type default)
			)
			(layer "B.Fab")
		)
		(fp_line
			(start 0.12065 0.3048)
			(end 0.67945 0.3048)
			(stroke
				(width 0.1)
				(type default)
			)
			(layer "B.Fab")
		)
		(fp_line
			(start -0.120396 0.3048)
			(end -0.120396 0.2794)
			(stroke
				(width 0.1)
				(type default)
			)
			(layer "B.Fab")
		)
		(fp_line
			(start -0.67945 0.3048)
			(end -0.120396 0.3048)
			(stroke
				(width 0.1)
				(type default)
			)
			(layer "B.Fab")
		)
		(pad "1" smd circle
			(at 0.40005 0 270)
			(size 0 0)
			(layers "B.Cu" "B.Mask" "B.Paste")
			(net "FM_SMB_PEHPCPU1_PCIE_ALERT_N")
		)
		(pad "2" smd circle
			(at -0.40005 0 270)
			(size 0 0)
			(layers "B.Cu" "B.Mask" "B.Paste")
			(net "FM_SMB_PEHPCPU1_PCIE_ALERT_R_N")
		)
	)
)
